# T6G (Grand Teton) — schematic netlist excerpt (pin names and nets, part order shuffled) for the footprints in the layout excerpt that follows; sources: Cadence DE-HDL packaged netlist, KiCad conversion of 04192023_DAF0TMB3IC0_F0TG_MB_C_brd_V02_OCP.brd

C866  Q_CAP_DIFFBUS  DIFF BUS_0.22UF 6.3V 20% X6S  pkg C0201  page 64 : \1\ = P5E_CPU0_P2_TX_C_DN<1> ; \2\ = P5E_CPU0_P2_TX_DN<1>

DB4  TDR_3P  EMPTY  pkg TH2  page 260
  GND  = T1_GND
  IO1  = TDR_SE_45_OHM_IN3
  IO2  = TDR_SE_45_OHM_IN3

C93  Q_CAP  15PF 50V 5% C0G  pkg 0402  page 176 : A = XTAL_USB_CPU0_HUB1_XOUT ; B = GND

(kicad_pcb
	(version 20260206)
	(generator "pcbnew")
	(generator_version "10.0")
	(general
		(thickness 1.6)
		(legacy_teardrops no)
	)
	(paper "A4")
	(title_block
		(title "04192023_DAF0TMB3IC0_F0TG_MB_C_brd_V02_OCP.brd")
		(comment 1 "Grand Teton / footprints 3935-3937 of 8354")
	)
	(layers
		(0 "F.Cu" signal "TOP")
		(4 "In1.Cu" signal "GND")
		(6 "In2.Cu" signal "IN1")
		(8 "In3.Cu" signal "GND1")
		(10 "In4.Cu" signal "IN2")
		(12 "In5.Cu" signal "GND2")
		(14 "In6.Cu" signal "IN3")
		(16 "In7.Cu" signal "GND3")
		(18 "In8.Cu" signal "VCC")
		(20 "In9.Cu" signal "VCC1")
		(22 "In10.Cu" signal "GND4")
		(24 "In11.Cu" signal "IN4")
		(26 "In12.Cu" signal "GND5")
		(28 "In13.Cu" signal "IN5")
		(30 "In14.Cu" signal "GND6")
		(32 "In15.Cu" signal "IN6")
		(34 "In16.Cu" signal "GND7")
		(2 "B.Cu" signal "BOTTOM")
		(9 "F.Adhes" user "F.Adhesive")
		(11 "B.Adhes" user "B.Adhesive")
		(13 "F.Paste" user "Package Geometry/Pastemask Top")
		(15 "B.Paste" user "Package Geometry/Pastemask Bottom")
		(5 "F.SilkS" user "Ref Des/Silkscreen Top")
		(7 "B.SilkS" user "Ref Des/Silkscreen Bottom")
		(1 "F.Mask" user "Board Geometry/Soldermask Top")
		(3 "B.Mask" user "Board Geometry/Soldermask Bottom")
		(17 "Dwgs.User" user "User.Drawings")
		(19 "Cmts.User" user "User.Comments")
		(21 "Eco1.User" user "User.Eco1")
		(23 "Eco2.User" user "User.Eco2")
		(25 "Edge.Cuts" user "Board Geometry/Outline")
		(27 "Margin" user)
		(31 "F.CrtYd" user "Package Geometry/Place Bound Top")
		(29 "B.CrtYd" user "Package Geometry/Place Bound Bottom")
		(35 "F.Fab" user "Ref Des/Assembly Top")
		(33 "B.Fab" user "Ref Des/Assembly Bottom")
	)
	(footprint ""
		(layer "F.Cu")
		(at 398.595088 -385.23926 180)
		(property "Reference" "C866"
			(at 0 0 180)
			(layer "F.SilkS")
			(hide yes)
			(effects
				(font
					(size 1.27 1.27)
				)
			)
		)
		(property "Value" ""
			(at 0 0 180)
			(layer "F.Fab")
			(effects
				(font
					(size 1.27 1.27)
				)
			)
		)
		(duplicate_pad_numbers_are_jumpers no)
		(fp_line
			(start 0.299974 0.150114)
			(end -0.299974 0.150114)
			(stroke
				(width 0.1)
				(type default)
			)
			(layer "F.Fab")
		)
		(fp_line
			(start 0.299974 -0.150114)
			(end 0.299974 0.150114)
			(stroke
				(width 0.1)
				(type default)
			)
			(layer "F.Fab")
		)
		(fp_line
			(start -0.299974 0.150114)
			(end -0.299974 -0.150114)
			(stroke
				(width 0.1)
				(type default)
			)
			(layer "F.Fab")
		)
		(fp_line
			(start -0.299974 -0.150114)
			(end 0.299974 -0.150114)
			(stroke
				(width 0.1)
				(type default)
			)
			(layer "F.Fab")
		)
		(pad "1" smd rect
			(at -0.2667 0 180)
			(size 0.3048 0.381)
			(layers "F.Cu" "F.Mask" "F.Paste")
			(net "P5E_CPU0_P2_TX_C_DN<1>")
		)
		(pad "2" smd rect
			(at 0.2667 0 180)
			(size 0.3048 0.381)
			(layers "F.Cu" "F.Mask" "F.Paste")
			(net "P5E_CPU0_P2_TX_DN<1>")
		)
	)
	(footprint ""
		(layer "F.Cu")
		(at 126.571756 -29.697172 90)
		(property "Reference" "C93"
			(at 0 0 90)
			(layer "F.SilkS")
			(hide yes)
			(effects
				(font
					(size 1.27 1.27)
				)
			)
		)
		(property "Value" ""
			(at 0 0 90)
			(layer "F.Fab")
			(effects
				(font
					(size 1.27 1.27)
				)
			)
		)
		(duplicate_pad_numbers_are_jumpers no)
		(fp_line
			(start 0.7874 -0.4064)
			(end 0.7874 0.4064)
			(stroke
				(width 0.1524)
				(type default)
			)
			(layer "F.SilkS")
		)
		(fp_line
			(start -0.7874 -0.4064)
			(end 0.7874 -0.4064)
			(stroke
				(width 0.1524)
				(type default)
			)
			(layer "F.SilkS")
		)
		(fp_line
			(start 0.7874 0.4064)
			(end -0.7874 0.4064)
			(stroke
				(width 0.1524)
				(type default)
			)
			(layer "F.SilkS")
		)
		(fp_line
			(start -0.7874 0.4064)
			(end -0.7874 -0.4064)
			(stroke
				(width 0.1524)
				(type default)
			)
			(layer "F.SilkS")
		)
		(fp_line
			(start -0.12065 -0.305054)
			(end -0.12065 -0.2794)
			(stroke
				(width 0.1)
				(type default)
			)
			(layer "F.Fab")
		)
		(fp_line
			(start -0.67945 -0.305054)
			(end -0.12065 -0.305054)
			(stroke
				(width 0.1)
				(type default)
			)
			(layer "F.Fab")
		)
		(fp_line
			(start 0.67945 -0.3048)
			(end 0.67945 0.3048)
			(stroke
				(width 0.1)
				(type default)
			)
			(layer "F.Fab")
		)
		(fp_line
			(start 0.12065 -0.3048)
			(end 0.67945 -0.3048)
			(stroke
				(width 0.1)
				(type default)
			)
			(layer "F.Fab")
		)
		(fp_line
			(start 0.12065 -0.2794)
			(end 0.12065 -0.3048)
			(stroke
				(width 0.1)
				(type default)
			)
			(layer "F.Fab")
		)
		(fp_line
			(start -0.12065 -0.2794)
			(end 0.12065 -0.2794)
			(stroke
				(width 0.1)
				(type default)
			)
			(layer "F.Fab")
		)
		(fp_line
			(start 0.120396 0.2794)
			(end -0.12065 0.2794)
			(stroke
				(width 0.1)
				(type default)
			)
			(layer "F.Fab")
		)
		(fp_line
			(start -0.12065 0.2794)
			(end -0.12065 0.3048)
			(stroke
				(width 0.1)
				(type default)
			)
			(layer "F.Fab")
		)
		(fp_line
			(start 0.67945 0.3048)
			(end 0.120396 0.3048)
			(stroke
				(width 0.1)
				(type default)
			)
			(layer "F.Fab")
		)
		(fp_line
			(start 0.120396 0.3048)
			(end 0.120396 0.2794)
			(stroke
				(width 0.1)
				(type default)
			)
			(layer "F.Fab")
		)
		(fp_line
			(start -0.12065 0.3048)
			(end -0.67945 0.3048)
			(stroke
				(width 0.1)
				(type default)
			)
			(layer "F.Fab")
		)
		(fp_line
			(start -0.67945 0.3048)
			(end -0.67945 -0.305054)
			(stroke
				(width 0.1)
				(type default)
			)
			(layer "F.Fab")
		)
		(pad "1" smd circle
			(at -0.40005 0 90)
			(size 0 0)
			(layers "F.Cu" "F.Mask" "F.Paste")
			(net "XTAL_USB_CPU0_HUB1_XOUT")
		)
		(pad "2" smd circle
			(at 0.40005 0 90)
			(size 0 0)
			(layers "F.Cu" "F.Mask" "F.Paste")
			(net "GND")
		)
	)
	(footprint ""
		(layer "F.Cu")
		(at 479.445066 -297.569128 180)
		(property "Reference" "DB4"
			(at -3.05943 -2.144014 0)
			(unlocked yes)
			(layer "F.SilkS")
			(effects
				(font
					(size 0.7874 0.5842)
					(thickness 0.1524)
				)
				(justify left)
			)
		)
		(property "Value" ""
			(at 0 0 180)
			(layer "F.Fab")
			(effects
				(font
					(size 1.27 1.27)
				)
			)
		)
		(duplicate_pad_numbers_are_jumpers no)
		(fp_line
			(start 3.330702 -4.771136)
			(end 3.21564 -4.46786)
			(stroke
				(width 0.1524)
				(type default)
			)
			(layer "F.SilkS")
		)
		(fp_line
			(start 2.502916 -2.588514)
			(end 0 4.011168)
			(stroke
				(width 0.1524)
				(type default)
			)
			(layer "F.SilkS")
		)
		(fp_line
			(start 0 4.011168)
			(end -3.330702 -4.771136)
			(stroke
				(width 0.1524)
				(type default)
			)
			(layer "F.SilkS")
		)
		(fp_line
			(start -3.330702 -4.771136)
			(end 3.330702 -4.771136)
			(stroke
				(width 0.1524)
				(type default)
			)
			(layer "F.SilkS")
		)
		(fp_line
			(start 3.330702 -4.771136)
			(end 0 4.011168)
			(stroke
				(width 0.1)
				(type default)
			)
			(layer "F.Fab")
		)
		(fp_line
			(start 0 4.011168)
			(end -3.330702 -4.771136)
			(stroke
				(width 0.1)
				(type default)
			)
			(layer "F.Fab")
		)
		(fp_line
			(start -3.330702 -4.771136)
			(end 3.330702 -4.771136)
			(stroke
				(width 0.1)
				(type default)
			)
			(layer "F.Fab")
		)
		(pad "1" thru_hole circle
			(at 0 0 180)
			(size 2.159 2.159)
			(drill 1.7018)
			(layers "*.Cu" "*.Mask")
			(remove_unused_layers no)
			(net "T1_GND")
			(clearance 0.0254)
			(thermal_gap 0.0254)
		)
		(pad "2" thru_hole circle
			(at -1.27 -3.348736 180)
			(size 2.159 2.159)
			(drill 1.7018)
			(layers "*.Cu" "*.Mask")
			(remove_unused_layers no)
			(net "TDR_SE_45_OHM_IN3")
			(clearance 0.0254)
			(thermal_gap 0.0254)
		)
		(pad "3" thru_hole circle
			(at 1.27 -3.348736 180)
			(size 2.159 2.159)
			(drill 1.7018)
			(layers "*.Cu" "*.Mask")
			(remove_unused_layers no)
			(net "TDR_SE_45_OHM_IN3")
			(clearance 0.0254)
			(thermal_gap 0.0254)
		)
	)
)
